#ISCELL
  mstr_misc dns *
  *
#ISCELL
  pure_quanta quanta_title_block_c *
  *
#ISCELL
  pure_quanta_power cad_note *
  *
#CELL
  pure_quanta q_res *
  page433_i1
#CELL
  pure_quanta q_inductor *
  page433_i10
#ISCELL
  pure_quanta_power p1v0 *
  page433_i11
#CELL
  pure_quanta q_cap *
  page433_i12
#CELL
  pure_quanta q_cap *
  page433_i13
#ISCELL
  pure_quanta_power p1v0 *
  page433_i14
#CELL
  pure_quanta q_cap *
  page433_i15
#CELL
  pure_quanta q_cap *
  page433_i16
#CELL
  pure_quanta q_cap *
  page433_i17
#ISCELL
  pure_quanta_power universal_gnd *
  page433_i18
#CELL
  pure_quanta q_cap *
  page433_i19
#CELL
  pure_quanta q_res *
  page433_i2
#CELL
  pure_quanta q_cap *
  page433_i20
#CELL
  pure_quanta q_cap *
  page433_i21
#CELL
  pure_quanta q_cap *
  page433_i22
#ISCELL
  pure_quanta_power universal_gnd *
  page433_i23
#CELL
  pure_quanta q_cap *
  page433_i24
#CELL
  pure_quanta q_cap *
  page433_i25
#CELL
  pure_quanta q_cap *
  page433_i26
#CELL
  pure_quanta q_cap *
  page433_i27
#CELL
  pure_quanta q_cap *
  page433_i28
#ISCELL
  pure_quanta_power vcc_core *
  page433_i29
#ISCELL
  pure_quanta_power universal_gnd *
  page433_i3
#CELL
  pure_quanta q_cap *
  page433_i30
#ISCELL
  pure_quanta_power vcc_core *
  page433_i32
#ISCELL
  pure_quanta_power universal_gnd *
  page433_i34
#CELL
  pure_quanta q_cap *
  page433_i35
#CELL
  pure_quanta q_res *
  page433_i36
#CELL
  pure_quanta q_cap *
  page433_i37
#CELL
  pure_quanta q_cap *
  page433_i38
#CELL
  pure_quanta q_cap *
  page433_i39
#ISCELL
  pure_quanta_power p1v0 *
  page433_i4
#CELL
  pure_quanta q_cap *
  page433_i40
#CELL
  pure_quanta q_cap *
  page433_i41
#CELL
  pure_quanta q_cap *
  page433_i42
#CELL
  pure_quanta q_cap *
  page433_i43
#CELL
  pure_quanta q_cap *
  page433_i44
#CELL
  pure_quanta q_cap *
  page433_i45
#CELL
  pure_quanta q_cap *
  page433_i46
#CELL
  pure_quanta q_cap *
  page433_i47
#CELL
  pure_quanta q_cap *
  page433_i48
#CELL
  pure_quanta q_cap *
  page433_i49
#CELL
  pure_quanta q_cap *
  page433_i5
#CELL
  pure_quanta q_cap *
  page433_i50
#CELL
  pure_quanta q_cap *
  page433_i51
#CELL
  pure_quanta q_cap *
  page433_i52
#CELL
  pure_quanta q_cap *
  page433_i53
#CELL
  pure_quanta q_cap *
  page433_i54
#ISCELL
  pure_quanta_power universal_gnd *
  page433_i55
#CELL
  pure_quanta q_cap *
  page433_i56
#CELL
  pure_quanta q_cap *
  page433_i57
#CELL
  pure_quanta q_cap *
  page433_i59
#CELL
  pure_quanta q_cap *
  page433_i6
#CELL
  pure_quanta q_cap *
  page433_i60
#CELL
  pure_quanta q_cap *
  page433_i62
#CELL
  pure_quanta q_cap *
  page433_i63
#ISCELL
  pure_quanta_power universal_gnd *
  page433_i64
#CELL
  pure_quanta q_inductor *
  page433_i65
#CELL
  pure_quanta q_cap *
  page433_i66
#CELL
  pure_quanta q_cap *
  page433_i67
#ISCELL
  pure_quanta_power vcc_core *
  page433_i68
#CELL
  pure_quanta q_cap *
  page433_i69
#CELL
  pure_quanta q_res *
  page433_i7
#CELL
  pure_quanta q_cap *
  page433_i70
#CELL
  pure_quanta q_cap *
  page433_i71
#CELL
  pure_quanta q_cap *
  page433_i72
#CELL
  pure_quanta q_cap *
  page433_i73
#CELL
  pure_quanta q_cap *
  page433_i74
#CELL
  pure_quanta q_cap *
  page433_i75
#CELL
  pure_quanta q_cap *
  page433_i76
#CELL
  pure_quanta q_cap *
  page433_i77
#CELL
  pure_quanta q_cap *
  page433_i78
#CELL
  pure_quanta q_cap *
  page433_i79
#CELL
  pure_quanta q_cap *
  page433_i80
#CELL
  pure_quanta q_cap *
  page433_i81
#CELL
  pure_quanta q_cap *
  page433_i82
#ISCELL
  pure_quanta_power universal_gnd *
  page433_i83
#CELL
  pure_quanta q_cap *
  page433_i84
#CELL
  pure_quanta q_cap *
  page433_i85
#CELL
  pure_quanta q_cap *
  page433_i86
#CELL
  pure_quanta q_cap *
  page433_i87
#CELL
  pure_quanta q_inductor *
  page433_i88
#CELL
  pure_quanta q_res *
  page433_i89
#CELL
  pure_quanta q_cap *
  page433_i90
#CELL
  pure_quanta q_cap *
  page433_i91
#CELL
  pure_quanta q_cap *
  page433_i92
#CELL
  pure_quanta q_cap *
  page433_i93
#CELL
  pure_quanta q_capp *
  page433_i94
#CELL
  pure_quanta q_capp *
  page433_i95
#CELL
  pure_quanta q_cap *
  page433_i96
